# SCM (Grand Teton) — schematic netlist excerpt (pin names and nets, part order shuffled) for the footprints in the layout excerpt that follows; sources: Cadence DE-HDL packaged netlist, KiCad conversion of 12092022_DA0F0TMDCD0_F0T_Management_Board_D_brd_V3_OCP.brd

R106  Q_RES  0 5% EMPTY  pkg 0402LF  page 22 : A = RST_BMC_SRST_N ; B = RST_BMC_EXTRST_R2_N
R175  Q_RES  33.2 1% CHIP  pkg 0402LF  page 44 : A = SPI_BMC_BIOS_ROM_MOSI ; B = SPI_BMC_BIOS_ROM_R_MOSI
PC218  Q_CAP  22UF 16V 20% X6S  pkg C0805  page 52 : A = SW_P3V3_AUX_FLT ; B = GND

(kicad_pcb
	(version 20260206)
	(generator "pcbnew")
	(generator_version "10.0")
	(general
		(thickness 1.6)
		(legacy_teardrops no)
	)
	(paper "A4")
	(title_block
		(title "12092022_DA0F0TMDCD0_F0T_Management_Board_D_brd_V3_OCP.brd")
		(comment 1 "Grand Teton / footprints 503-505 of 1440")
	)
	(layers
		(0 "F.Cu" signal "TOP")
		(4 "In1.Cu" signal "GND")
		(6 "In2.Cu" signal "IN1")
		(8 "In3.Cu" signal "GND1")
		(10 "In4.Cu" signal "IN2")
		(12 "In5.Cu" signal "VCC")
		(14 "In6.Cu" signal "VCC1")
		(16 "In7.Cu" signal "IN3")
		(18 "In8.Cu" signal "GND2")
		(20 "In9.Cu" signal "IN4")
		(22 "In10.Cu" signal "GND3")
		(2 "B.Cu" signal "BOTTOM")
		(9 "F.Adhes" user "F.Adhesive")
		(11 "B.Adhes" user "B.Adhesive")
		(13 "F.Paste" user "Package Geometry/Pastemask Top")
		(15 "B.Paste" user "Package Geometry/Pastemask Bottom")
		(5 "F.SilkS" user "Ref Des/Silkscreen Top")
		(7 "B.SilkS" user "Ref Des/Silkscreen Bottom")
		(1 "F.Mask" user "Board Geometry/Soldermask Top")
		(3 "B.Mask" user "Board Geometry/Soldermask Bottom")
		(17 "Dwgs.User" user "User.Drawings")
		(19 "Cmts.User" user "User.Comments")
		(21 "Eco1.User" user "User.Eco1")
		(23 "Eco2.User" user "User.Eco2")
		(25 "Edge.Cuts" user "Board Geometry/Outline")
		(27 "Margin" user)
		(31 "F.CrtYd" user "Package Geometry/Place Bound Top")
		(29 "B.CrtYd" user "Package Geometry/Place Bound Bottom")
		(35 "F.Fab" user "Ref Des/Assembly Top")
		(33 "B.Fab" user "Ref Des/Assembly Bottom")
	)
	(footprint ""
		(layer "F.Cu")
		(at 66.3702 -63.9572 90)
		(property "Reference" "R175"
			(at 0 0 90)
			(layer "F.SilkS")
			(hide yes)
			(effects
				(font
					(size 1.27 1.27)
				)
			)
		)
		(property "Value" ""
			(at 0 0 90)
			(layer "F.Fab")
			(effects
				(font
					(size 1.27 1.27)
				)
			)
		)
		(duplicate_pad_numbers_are_jumpers no)
		(fp_line
			(start 0.7874 -0.4064)
			(end 0.7874 0.4064)
			(stroke
				(width 0.1524)
				(type default)
			)
			(layer "F.SilkS")
		)
		(fp_line
			(start -0.7874 -0.4064)
			(end 0.7874 -0.4064)
			(stroke
				(width 0.1524)
				(type default)
			)
			(layer "F.SilkS")
		)
		(fp_line
			(start 0.7874 0.4064)
			(end -0.7874 0.4064)
			(stroke
				(width 0.1524)
				(type default)
			)
			(layer "F.SilkS")
		)
		(fp_line
			(start -0.7874 0.4064)
			(end -0.7874 -0.4064)
			(stroke
				(width 0.1524)
				(type default)
			)
			(layer "F.SilkS")
		)
		(fp_line
			(start -0.12065 -0.305054)
			(end -0.12065 -0.2794)
			(stroke
				(width 0.1)
				(type default)
			)
			(layer "F.Fab")
		)
		(fp_line
			(start -0.67945 -0.305054)
			(end -0.12065 -0.305054)
			(stroke
				(width 0.1)
				(type default)
			)
			(layer "F.Fab")
		)
		(fp_line
			(start 0.67945 -0.3048)
			(end 0.67945 0.3048)
			(stroke
				(width 0.1)
				(type default)
			)
			(layer "F.Fab")
		)
		(fp_line
			(start 0.12065 -0.3048)
			(end 0.67945 -0.3048)
			(stroke
				(width 0.1)
				(type default)
			)
			(layer "F.Fab")
		)
		(fp_line
			(start 0.12065 -0.2794)
			(end 0.12065 -0.3048)
			(stroke
				(width 0.1)
				(type default)
			)
			(layer "F.Fab")
		)
		(fp_line
			(start -0.12065 -0.2794)
			(end 0.12065 -0.2794)
			(stroke
				(width 0.1)
				(type default)
			)
			(layer "F.Fab")
		)
		(fp_line
			(start 0.120396 0.2794)
			(end -0.12065 0.2794)
			(stroke
				(width 0.1)
				(type default)
			)
			(layer "F.Fab")
		)
		(fp_line
			(start -0.12065 0.2794)
			(end -0.12065 0.3048)
			(stroke
				(width 0.1)
				(type default)
			)
			(layer "F.Fab")
		)
		(fp_line
			(start 0.67945 0.3048)
			(end 0.120396 0.3048)
			(stroke
				(width 0.1)
				(type default)
			)
			(layer "F.Fab")
		)
		(fp_line
			(start 0.120396 0.3048)
			(end 0.120396 0.2794)
			(stroke
				(width 0.1)
				(type default)
			)
			(layer "F.Fab")
		)
		(fp_line
			(start -0.12065 0.3048)
			(end -0.67945 0.3048)
			(stroke
				(width 0.1)
				(type default)
			)
			(layer "F.Fab")
		)
		(fp_line
			(start -0.67945 0.3048)
			(end -0.67945 -0.305054)
			(stroke
				(width 0.1)
				(type default)
			)
			(layer "F.Fab")
		)
		(pad "1" smd circle
			(at -0.40005 0 90)
			(size 0 0)
			(layers "F.Cu" "F.Mask" "F.Paste")
			(net "SPI_BMC_BIOS_ROM_MOSI")
		)
		(pad "2" smd circle
			(at 0.40005 0 90)
			(size 0 0)
			(layers "F.Cu" "F.Mask" "F.Paste")
			(net "SPI_BMC_BIOS_ROM_R_MOSI")
		)
	)
	(footprint ""
		(layer "F.Cu")
		(at 54.229 -96.012 90)
		(property "Reference" "R106"
			(at 0 0 90)
			(layer "F.SilkS")
			(hide yes)
			(effects
				(font
					(size 1.27 1.27)
				)
			)
		)
		(property "Value" ""
			(at 0 0 90)
			(layer "F.Fab")
			(effects
				(font
					(size 1.27 1.27)
				)
			)
		)
		(duplicate_pad_numbers_are_jumpers no)
		(fp_line
			(start 0.7874 -0.4064)
			(end 0.7874 0.4064)
			(stroke
				(width 0.1524)
				(type default)
			)
			(layer "F.SilkS")
		)
		(fp_line
			(start -0.7874 -0.4064)
			(end 0.7874 -0.4064)
			(stroke
				(width 0.1524)
				(type default)
			)
			(layer "F.SilkS")
		)
		(fp_line
			(start 0.7874 0.4064)
			(end -0.7874 0.4064)
			(stroke
				(width 0.1524)
				(type default)
			)
			(layer "F.SilkS")
		)
		(fp_line
			(start -0.7874 0.4064)
			(end -0.7874 -0.4064)
			(stroke
				(width 0.1524)
				(type default)
			)
			(layer "F.SilkS")
		)
		(fp_line
			(start -0.12065 -0.305054)
			(end -0.12065 -0.2794)
			(stroke
				(width 0.1)
				(type default)
			)
			(layer "F.Fab")
		)
		(fp_line
			(start -0.67945 -0.305054)
			(end -0.12065 -0.305054)
			(stroke
				(width 0.1)
				(type default)
			)
			(layer "F.Fab")
		)
		(fp_line
			(start 0.67945 -0.3048)
			(end 0.67945 0.3048)
			(stroke
				(width 0.1)
				(type default)
			)
			(layer "F.Fab")
		)
		(fp_line
			(start 0.12065 -0.3048)
			(end 0.67945 -0.3048)
			(stroke
				(width 0.1)
				(type default)
			)
			(layer "F.Fab")
		)
		(fp_line
			(start 0.12065 -0.2794)
			(end 0.12065 -0.3048)
			(stroke
				(width 0.1)
				(type default)
			)
			(layer "F.Fab")
		)
		(fp_line
			(start -0.12065 -0.2794)
			(end 0.12065 -0.2794)
			(stroke
				(width 0.1)
				(type default)
			)
			(layer "F.Fab")
		)
		(fp_line
			(start 0.120396 0.2794)
			(end -0.12065 0.2794)
			(stroke
				(width 0.1)
				(type default)
			)
			(layer "F.Fab")
		)
		(fp_line
			(start -0.12065 0.2794)
			(end -0.12065 0.3048)
			(stroke
				(width 0.1)
				(type default)
			)
			(layer "F.Fab")
		)
		(fp_line
			(start 0.67945 0.3048)
			(end 0.120396 0.3048)
			(stroke
				(width 0.1)
				(type default)
			)
			(layer "F.Fab")
		)
		(fp_line
			(start 0.120396 0.3048)
			(end 0.120396 0.2794)
			(stroke
				(width 0.1)
				(type default)
			)
			(layer "F.Fab")
		)
		(fp_line
			(start -0.12065 0.3048)
			(end -0.67945 0.3048)
			(stroke
				(width 0.1)
				(type default)
			)
			(layer "F.Fab")
		)
		(fp_line
			(start -0.67945 0.3048)
			(end -0.67945 -0.305054)
			(stroke
				(width 0.1)
				(type default)
			)
			(layer "F.Fab")
		)
		(pad "1" smd circle
			(at -0.40005 0 90)
			(size 0 0)
			(layers "F.Cu" "F.Mask" "F.Paste")
			(net "RST_BMC_SRST_N")
		)
		(pad "2" smd circle
			(at 0.40005 0 90)
			(size 0 0)
			(layers "F.Cu" "F.Mask" "F.Paste")
			(net "RST_BMC_EXTRST_R2_N")
		)
	)
	(footprint ""
		(layer "F.Cu")
		(at 7.239 -61.087 180)
		(property "Reference" "PC218"
			(at 0 0 180)
			(layer "F.SilkS")
			(hide yes)
			(effects
				(font
					(size 1.27 1.27)
				)
			)
		)
		(property "Value" ""
			(at 0 0 180)
			(layer "F.Fab")
			(effects
				(font
					(size 1.27 1.27)
				)
			)
		)
		(duplicate_pad_numbers_are_jumpers no)
		(fp_line
			(start 1.524 0.762)
			(end -1.524 0.762)
			(stroke
				(width 0.1524)
				(type default)
			)
			(layer "F.SilkS")
		)
		(fp_line
			(start 1.524 -0.762)
			(end 1.524 0.762)
			(stroke
				(width 0.1524)
				(type default)
			)
			(layer "F.SilkS")
		)
		(fp_line
			(start -1.524 0.762)
			(end -1.524 -0.762)
			(stroke
				(width 0.1524)
				(type default)
			)
			(layer "F.SilkS")
		)
		(fp_line
			(start -1.524 -0.762)
			(end 1.524 -0.762)
			(stroke
				(width 0.1524)
				(type default)
			)
			(layer "F.SilkS")
		)
		(fp_line
			(start 1.1049 0.724916)
			(end 1.1049 -0.724916)
			(stroke
				(width 0.1)
				(type default)
			)
			(layer "F.Fab")
		)
		(fp_line
			(start 1.1049 -0.724916)
			(end -1.1049 -0.724916)
			(stroke
				(width 0.1)
				(type default)
			)
			(layer "F.Fab")
		)
		(fp_line
			(start -1.1049 0.724916)
			(end 1.1049 0.724916)
			(stroke
				(width 0.1)
				(type default)
			)
			(layer "F.Fab")
		)
		(fp_line
			(start -1.1049 -0.724916)
			(end -1.1049 0.724916)
			(stroke
				(width 0.1)
				(type default)
			)
			(layer "F.Fab")
		)
		(pad "1" smd rect
			(at -0.889 0)
			(size 1.016 1.27)
			(layers "F.Cu" "F.Mask" "F.Paste")
			(net "SW_P3V3_AUX_FLT")
		)
		(pad "2" smd rect
			(at 0.889 0)
			(size 1.016 1.27)
			(layers "F.Cu" "F.Mask" "F.Paste")
			(net "GND")
		)
	)
)
